# S9S_MB_2U (Grand Teton) — schematic netlist excerpt (pin names and nets, part order shuffled) for the footprints in the layout excerpt that follows; sources: Cadence DE-HDL packaged netlist, KiCad conversion of 03242023_DA0F0TMBIJ0_F0T_Motherboard_J_brd_V01_OCP.brd

C247  Q_CAP  10UF 6.3V 20% X6S  pkg C0402  page 77 : A = PVCCIN_CPU1 ; B = GND
R3616  Q_RES  4.7K 1% CHIP  pkg 0402LF  page 171 : A = GND ; B = INA230_1_A1

(kicad_pcb
	(version 20260206)
	(generator "pcbnew")
	(generator_version "10.0")
	(general
		(thickness 1.6)
		(legacy_teardrops no)
	)
	(paper "A4")
	(title_block
		(title "03242023_DA0F0TMBIJ0_F0T_Motherboard_J_brd_V01_OCP.brd")
		(comment 1 "Grand Teton / footprints 2726-2727 of 6105")
	)
	(layers
		(0 "F.Cu" signal "TOP")
		(4 "In1.Cu" signal "GND")
		(6 "In2.Cu" signal "IN1")
		(8 "In3.Cu" signal "GND1")
		(10 "In4.Cu" signal "IN2")
		(12 "In5.Cu" signal "GND2")
		(14 "In6.Cu" signal "IN3")
		(16 "In7.Cu" signal "GND3")
		(18 "In8.Cu" signal "VCC")
		(20 "In9.Cu" signal "VCC1")
		(22 "In10.Cu" signal "GND4")
		(24 "In11.Cu" signal "IN4")
		(26 "In12.Cu" signal "GND5")
		(28 "In13.Cu" signal "IN5")
		(30 "In14.Cu" signal "GND6")
		(32 "In15.Cu" signal "IN6")
		(34 "In16.Cu" signal "GND7")
		(2 "B.Cu" signal "BOTTOM")
		(9 "F.Adhes" user "F.Adhesive")
		(11 "B.Adhes" user "B.Adhesive")
		(13 "F.Paste" user "Package Geometry/Pastemask Top")
		(15 "B.Paste" user "Package Geometry/Pastemask Bottom")
		(5 "F.SilkS" user "Ref Des/Silkscreen Top")
		(7 "B.SilkS" user "Ref Des/Silkscreen Bottom")
		(1 "F.Mask" user "Board Geometry/Soldermask Top")
		(3 "B.Mask" user "Board Geometry/Soldermask Bottom")
		(17 "Dwgs.User" user "User.Drawings")
		(19 "Cmts.User" user "User.Comments")
		(21 "Eco1.User" user "User.Eco1")
		(23 "Eco2.User" user "User.Eco2")
		(25 "Edge.Cuts" user "Board Geometry/Outline")
		(27 "Margin" user)
		(31 "F.CrtYd" user "Package Geometry/Place Bound Top")
		(29 "B.CrtYd" user "Package Geometry/Place Bound Bottom")
		(35 "F.Fab" user "Ref Des/Assembly Top")
		(33 "B.Fab" user "Ref Des/Assembly Bottom")
	)
	(footprint ""
		(layer "F.Cu")
		(at 448.672458 -92.493592 180)
		(property "Reference" "R3616"
			(at 0 0 180)
			(layer "F.SilkS")
			(hide yes)
			(effects
				(font
					(size 1.27 1.27)
				)
			)
		)
		(property "Value" ""
			(at 0 0 180)
			(layer "F.Fab")
			(effects
				(font
					(size 1.27 1.27)
				)
			)
		)
		(duplicate_pad_numbers_are_jumpers no)
		(fp_line
			(start 0.7874 0.4064)
			(end -0.7874 0.4064)
			(stroke
				(width 0.1524)
				(type default)
			)
			(layer "F.SilkS")
		)
		(fp_line
			(start 0.7874 -0.4064)
			(end 0.7874 0.4064)
			(stroke
				(width 0.1524)
				(type default)
			)
			(layer "F.SilkS")
		)
		(fp_line
			(start -0.7874 0.4064)
			(end -0.7874 -0.4064)
			(stroke
				(width 0.1524)
				(type default)
			)
			(layer "F.SilkS")
		)
		(fp_line
			(start -0.7874 -0.4064)
			(end 0.7874 -0.4064)
			(stroke
				(width 0.1524)
				(type default)
			)
			(layer "F.SilkS")
		)
		(fp_line
			(start 0.67945 0.3048)
			(end 0.120396 0.3048)
			(stroke
				(width 0.1)
				(type default)
			)
			(layer "F.Fab")
		)
		(fp_line
			(start 0.67945 -0.3048)
			(end 0.67945 0.3048)
			(stroke
				(width 0.1)
				(type default)
			)
			(layer "F.Fab")
		)
		(fp_line
			(start 0.12065 -0.2794)
			(end 0.12065 -0.3048)
			(stroke
				(width 0.1)
				(type default)
			)
			(layer "F.Fab")
		)
		(fp_line
			(start 0.12065 -0.3048)
			(end 0.67945 -0.3048)
			(stroke
				(width 0.1)
				(type default)
			)
			(layer "F.Fab")
		)
		(fp_line
			(start 0.120396 0.3048)
			(end 0.120396 0.2794)
			(stroke
				(width 0.1)
				(type default)
			)
			(layer "F.Fab")
		)
		(fp_line
			(start 0.120396 0.2794)
			(end -0.12065 0.2794)
			(stroke
				(width 0.1)
				(type default)
			)
			(layer "F.Fab")
		)
		(fp_line
			(start -0.12065 0.3048)
			(end -0.67945 0.3048)
			(stroke
				(width 0.1)
				(type default)
			)
			(layer "F.Fab")
		)
		(fp_line
			(start -0.12065 0.2794)
			(end -0.12065 0.3048)
			(stroke
				(width 0.1)
				(type default)
			)
			(layer "F.Fab")
		)
		(fp_line
			(start -0.12065 -0.2794)
			(end 0.12065 -0.2794)
			(stroke
				(width 0.1)
				(type default)
			)
			(layer "F.Fab")
		)
		(fp_line
			(start -0.12065 -0.305054)
			(end -0.12065 -0.2794)
			(stroke
				(width 0.1)
				(type default)
			)
			(layer "F.Fab")
		)
		(fp_line
			(start -0.67945 0.3048)
			(end -0.67945 -0.305054)
			(stroke
				(width 0.1)
				(type default)
			)
			(layer "F.Fab")
		)
		(fp_line
			(start -0.67945 -0.305054)
			(end -0.12065 -0.305054)
			(stroke
				(width 0.1)
				(type default)
			)
			(layer "F.Fab")
		)
		(pad "1" smd circle
			(at -0.40005 0 180)
			(size 0 0)
			(layers "F.Cu" "F.Mask" "F.Paste")
			(net "GND")
		)
		(pad "2" smd circle
			(at 0.40005 0 180)
			(size 0 0)
			(layers "F.Cu" "F.Mask" "F.Paste")
			(net "INA230_1_A1")
		)
	)
	(footprint ""
		(layer "F.Cu")
		(at 104.34193 -241.97691 -90)
		(property "Reference" "C247"
			(at 0 0 270)
			(layer "F.SilkS")
			(hide yes)
			(effects
				(font
					(size 1.27 1.27)
				)
			)
		)
		(property "Value" ""
			(at 0 0 270)
			(layer "F.Fab")
			(effects
				(font
					(size 1.27 1.27)
				)
			)
		)
		(duplicate_pad_numbers_are_jumpers no)
		(fp_line
			(start -0.7874 0.4064)
			(end -0.7874 -0.4064)
			(stroke
				(width 0.1524)
				(type default)
			)
			(layer "F.SilkS")
		)
		(fp_line
			(start 0.7874 0.4064)
			(end -0.7874 0.4064)
			(stroke
				(width 0.1524)
				(type default)
			)
			(layer "F.SilkS")
		)
		(fp_line
			(start -0.7874 -0.4064)
			(end 0.7874 -0.4064)
			(stroke
				(width 0.1524)
				(type default)
			)
			(layer "F.SilkS")
		)
		(fp_line
			(start 0.7874 -0.4064)
			(end 0.7874 0.4064)
			(stroke
				(width 0.1524)
				(type default)
			)
			(layer "F.SilkS")
		)
		(fp_line
			(start -0.67945 0.3048)
			(end -0.67945 -0.305054)
			(stroke
				(width 0.1)
				(type default)
			)
			(layer "F.Fab")
		)
		(fp_line
			(start -0.12065 0.3048)
			(end -0.67945 0.3048)
			(stroke
				(width 0.1)
				(type default)
			)
			(layer "F.Fab")
		)
		(fp_line
			(start 0.120396 0.3048)
			(end 0.120396 0.2794)
			(stroke
				(width 0.1)
				(type default)
			)
			(layer "F.Fab")
		)
		(fp_line
			(start 0.67945 0.3048)
			(end 0.120396 0.3048)
			(stroke
				(width 0.1)
				(type default)
			)
			(layer "F.Fab")
		)
		(fp_line
			(start -0.12065 0.2794)
			(end -0.12065 0.3048)
			(stroke
				(width 0.1)
				(type default)
			)
			(layer "F.Fab")
		)
		(fp_line
			(start 0.120396 0.2794)
			(end -0.12065 0.2794)
			(stroke
				(width 0.1)
				(type default)
			)
			(layer "F.Fab")
		)
		(fp_line
			(start -0.12065 -0.2794)
			(end 0.12065 -0.2794)
			(stroke
				(width 0.1)
				(type default)
			)
			(layer "F.Fab")
		)
		(fp_line
			(start 0.12065 -0.2794)
			(end 0.12065 -0.3048)
			(stroke
				(width 0.1)
				(type default)
			)
			(layer "F.Fab")
		)
		(fp_line
			(start 0.12065 -0.3048)
			(end 0.67945 -0.3048)
			(stroke
				(width 0.1)
				(type default)
			)
			(layer "F.Fab")
		)
		(fp_line
			(start 0.67945 -0.3048)
			(end 0.67945 0.3048)
			(stroke
				(width 0.1)
				(type default)
			)
			(layer "F.Fab")
		)
		(fp_line
			(start -0.67945 -0.305054)
			(end -0.12065 -0.305054)
			(stroke
				(width 0.1)
				(type default)
			)
			(layer "F.Fab")
		)
		(fp_line
			(start -0.12065 -0.305054)
			(end -0.12065 -0.2794)
			(stroke
				(width 0.1)
				(type default)
			)
			(layer "F.Fab")
		)
		(pad "1" smd circle
			(at -0.40005 0 270)
			(size 0 0)
			(layers "F.Cu" "F.Mask" "F.Paste")
			(net "PVCCIN_CPU1")
		)
		(pad "2" smd circle
			(at 0.40005 0 270)
			(size 0 0)
			(layers "F.Cu" "F.Mask" "F.Paste")
			(net "GND")
		)
	)
)
